(kicad_pcb
	(version 20241229)
	(generator "pcbnew")
	(generator_version "9.0")
	(general
		(thickness 1.599998)
		(legacy_teardrops no)
	)
	(paper "A4")
	(title_block
		(title "Artix - Datacenter Secure Control Module (DC-SCM)")
		(date "2024-11-06")
		(rev "1.1.3")
		(comment 9 "footprints 277-282 of 544")
	)
	(layers
		(0 "F.Cu" signal)
		(4 "In1.Cu" signal)
		(6 "In2.Cu" signal)
		(8 "In3.Cu" signal)
		(10 "In4.Cu" signal)
		(12 "In5.Cu" signal)
		(14 "In6.Cu" signal)
		(2 "B.Cu" signal)
		(9 "F.Adhes" user "F.Adhesive")
		(11 "B.Adhes" user "B.Adhesive")
		(13 "F.Paste" user)
		(15 "B.Paste" user)
		(5 "F.SilkS" user "F.Silkscreen")
		(7 "B.SilkS" user "B.Silkscreen")
		(1 "F.Mask" user)
		(3 "B.Mask" user)
		(17 "Dwgs.User" user "User.Drawings")
		(19 "Cmts.User" user "User.Comments")
		(21 "Eco1.User" user "User.Eco1")
		(23 "Eco2.User" user "User.Eco2")
		(25 "Edge.Cuts" user)
		(27 "Margin" user)
		(31 "F.CrtYd" user "F.Courtyard")
		(29 "B.CrtYd" user "B.Courtyard")
		(35 "F.Fab" user)
		(33 "B.Fab" user)
	)
	(footprint "antmicro-footprints:C_0603_1608Metric"
		(layer "B.Cu")
		(at 90.5 153)
		(descr "Capacitor SMD 0603")
		(tags "capacitor 0603")
		(property "Reference" "C108"
			(at -3.9 0.4 0)
			(layer "B.SilkS")
			(effects
				(font
					(size 0.7 0.7)
					(thickness 0.15)
				)
				(justify right bottom mirror)
			)
		)
		(property "Value" "C_4u7_0603"
			(at 0 -1.6 0)
			(layer "B.Fab")
			(effects
				(font
					(size 0.7 0.7)
					(thickness 0.15)
				)
				(justify right bottom mirror)
			)
		)
		(property "Datasheet" "https://product.tdk.com/en/search/capacitor/ceramic/mlcc/info?part_no=C1608X5R1V475M080AC"
			(at 0 0 0)
			(layer "F.Fab")
			(hide yes)
			(effects
				(font
					(size 1.27 1.27)
					(thickness 0.15)
				)
			)
		)
		(property "Description" "SMD Multilayer Ceramic Capacitor, 4.7 µF, 35 V, 0603 [1608 Metric], ± 20%, X5R, C"
			(at 0 0 0)
			(layer "F.Fab")
			(hide yes)
			(effects
				(font
					(size 1.27 1.27)
					(thickness 0.15)
				)
			)
		)
		(property "Author" "Antmicro"
			(at 0 0 0)
			(layer "B.Fab")
			(hide yes)
			(effects
				(font
					(size 1 1)
					(thickness 0.15)
				)
				(justify mirror)
			)
		)
		(property "Dielectric" ""
			(at 0 0 0)
			(layer "B.Fab")
			(hide yes)
			(effects
				(font
					(size 1 1)
					(thickness 0.15)
				)
				(justify mirror)
			)
		)
		(property "License" "Apache-2.0"
			(at 0 0 0)
			(layer "B.Fab")
			(hide yes)
			(effects
				(font
					(size 1 1)
					(thickness 0.15)
				)
				(justify mirror)
			)
		)
		(property "MPN" "C1608X5R1V475M080AC"
			(at 0 0 0)
			(layer "B.Fab")
			(hide yes)
			(effects
				(font
					(size 1 1)
					(thickness 0.15)
				)
				(justify mirror)
			)
		)
		(property "Manufacturer" "TDK"
			(at 0 0 0)
			(layer "B.Fab")
			(hide yes)
			(effects
				(font
					(size 1 1)
					(thickness 0.15)
				)
				(justify mirror)
			)
		)
		(property "Val" "4u7"
			(at 0 0 0)
			(layer "B.Fab")
			(hide yes)
			(effects
				(font
					(size 1 1)
					(thickness 0.15)
				)
				(justify mirror)
			)
		)
		(property "Voltage" ""
			(at 0 0 0)
			(layer "B.Fab")
			(hide yes)
			(effects
				(font
					(size 1 1)
					(thickness 0.15)
				)
				(justify mirror)
			)
		)
		(property "DNP" ""
			(at 0 0 0)
			(unlocked yes)
			(layer "B.Fab")
			(hide yes)
			(effects
				(font
					(size 1 1)
					(thickness 0.15)
				)
				(justify mirror)
			)
		)
		(sheetname "/FPGA banks 34-35 & CFG/")
		(sheetfile "fpga-banks-34-25-cfg.kicad_sch")
		(attr smd)
		(fp_line
			(start -0.15 -0.4)
			(end 0.15 -0.4)
			(stroke
				(width 0.15)
				(type solid)
			)
			(layer "B.SilkS")
		)
		(fp_line
			(start -0.15 0.4)
			(end 0.15 0.4)
			(stroke
				(width 0.15)
				(type solid)
			)
			(layer "B.SilkS")
		)
		(fp_rect
			(start -1.25 0.65)
			(end 1.25 -0.65)
			(stroke
				(width 0.05)
				(type solid)
			)
			(fill no)
			(layer "B.CrtYd")
		)
		(fp_rect
			(start -0.8 0.4)
			(end 0.8 -0.4)
			(stroke
				(width 0.15)
				(type solid)
			)
			(fill no)
			(layer "B.Fab")
		)
		(pad "1" smd roundrect
			(at -0.7 0)
			(size 0.8 1)
			(layers "B.Cu" "B.Mask" "B.Paste")
			(roundrect_rratio 0.2)
			(net 1 "GND")
			(pintype "passive")
		)
		(pad "2" smd roundrect
			(at 0.7 0)
			(size 0.8 1)
			(layers "B.Cu" "B.Mask" "B.Paste")
			(roundrect_rratio 0.2)
			(net 3 "VCC1V35")
			(pintype "passive")
		)
	)
	(footprint "antmicro-footprints:C_1210_3225Metric"
		(layer "B.Cu")
		(at 92.8 99.5 180)
		(descr "Capacitor SMD 1210")
		(tags "capacitor SMD 1210")
		(property "Reference" "C133"
			(at 5.4 0.6 0)
			(layer "B.SilkS")
			(effects
				(font
					(size 0.7 0.7)
					(thickness 0.15)
				)
				(justify left bottom mirror)
			)
		)
		(property "Value" "C_47u_1210"
			(at 0 -2.749 0)
			(layer "B.Fab")
			(effects
				(font
					(size 0.7 0.7)
					(thickness 0.15)
				)
				(justify left bottom mirror)
			)
		)
		(property "Datasheet" "https://www.kemet.com/en/us/capacitors/product/C1210C476K8RACTU.html"
			(at 0 0 180)
			(layer "F.Fab")
			(hide yes)
			(effects
				(font
					(size 1.27 1.27)
					(thickness 0.15)
				)
			)
		)
		(property "Description" "SMD Multilayer Ceramic Capacitor, 47 µF, 10 V, 1210 [3225 Metric], ± 10%, X7R, C Series KEMET"
			(at 0 0 180)
			(layer "F.Fab")
			(hide yes)
			(effects
				(font
					(size 1.27 1.27)
					(thickness 0.15)
				)
			)
		)
		(property "Author" "Antmicro"
			(at 185.6 199 0)
			(layer "B.Fab")
			(hide yes)
			(effects
				(font
					(size 1 1)
					(thickness 0.15)
				)
				(justify mirror)
			)
		)
		(property "Dielectric" ""
			(at 185.6 199 0)
			(layer "B.Fab")
			(hide yes)
			(effects
				(font
					(size 1 1)
					(thickness 0.15)
				)
				(justify mirror)
			)
		)
		(property "License" "Apache-2.0"
			(at 185.6 199 0)
			(layer "B.Fab")
			(hide yes)
			(effects
				(font
					(size 1 1)
					(thickness 0.15)
				)
				(justify mirror)
			)
		)
		(property "MPN" "C1210C476K8RACTU"
			(at 185.6 199 0)
			(layer "B.Fab")
			(hide yes)
			(effects
				(font
					(size 1 1)
					(thickness 0.15)
				)
				(justify mirror)
			)
		)
		(property "Manufacturer" "KEMET"
			(at 185.6 199 0)
			(layer "B.Fab")
			(hide yes)
			(effects
				(font
					(size 1 1)
					(thickness 0.15)
				)
				(justify mirror)
			)
		)
		(property "Public" "False"
			(at 185.6 199 0)
			(layer "B.Fab")
			(hide yes)
			(effects
				(font
					(size 1 1)
					(thickness 0.15)
				)
				(justify mirror)
			)
		)
		(property "Val" "47u"
			(at 185.6 199 0)
			(layer "B.Fab")
			(hide yes)
			(effects
				(font
					(size 1 1)
					(thickness 0.15)
				)
				(justify mirror)
			)
		)
		(property "Voltage" ""
			(at 185.6 199 0)
			(layer "B.Fab")
			(hide yes)
			(effects
				(font
					(size 1 1)
					(thickness 0.15)
				)
				(justify mirror)
			)
		)
		(sheetname "/FPGA power supply/")
		(sheetfile "fpga-power-supply.kicad_sch")
		(attr smd)
		(fp_line
			(start -0.3 1.39)
			(end 0.3 1.39)
			(stroke
				(width 0.15)
				(type solid)
			)
			(layer "B.SilkS")
		)
		(fp_line
			(start -0.3 -1.39)
			(end 0.3 -1.39)
			(stroke
				(width 0.15)
				(type solid)
			)
			(layer "B.SilkS")
		)
		(fp_rect
			(start -2.1 1.75)
			(end 2.1 -1.75)
			(stroke
				(width 0.05)
				(type solid)
			)
			(fill no)
			(layer "B.CrtYd")
		)
		(fp_rect
			(start -1.6 1.25)
			(end 1.6 -1.25)
			(stroke
				(width 0.15)
				(type solid)
			)
			(fill no)
			(layer "B.Fab")
		)
		(pad "1" smd rect
			(at -1.145 0 180)
			(size 1.52 3.05)
			(layers "B.Cu" "B.Mask" "B.Paste")
			(net 1 "GND")
			(pintype "passive")
		)
		(pad "2" smd rect
			(at 1.145 0 180)
			(size 1.52 3.05)
			(layers "B.Cu" "B.Mask" "B.Paste")
			(net 5 "VCC1V8")
			(pintype "passive")
		)
	)
	(footprint "antmicro-footprints:C_0603_1608Metric"
		(layer "B.Cu")
		(at 92.8 96.9 180)
		(descr "Capacitor SMD 0603")
		(tags "capacitor 0603")
		(property "Reference" "C137"
			(at 5.4 -0.2 0)
			(layer "B.SilkS")
			(effects
				(font
					(size 0.7 0.7)
					(thickness 0.15)
				)
				(justify left bottom mirror)
			)
		)
		(property "Value" "C_4u7_0603"
			(at 0 -1.6 0)
			(layer "B.Fab")
			(effects
				(font
					(size 0.7 0.7)
					(thickness 0.15)
				)
				(justify left bottom mirror)
			)
		)
		(property "Datasheet" "https://product.tdk.com/en/search/capacitor/ceramic/mlcc/info?part_no=C1608X5R1V475M080AC"
			(at 0 0 180)
			(layer "F.Fab")
			(hide yes)
			(effects
				(font
					(size 1.27 1.27)
					(thickness 0.15)
				)
			)
		)
		(property "Description" "SMD Multilayer Ceramic Capacitor, 4.7 µF, 35 V, 0603 [1608 Metric], ± 20%, X5R, C"
			(at 0 0 180)
			(layer "F.Fab")
			(hide yes)
			(effects
				(font
					(size 1.27 1.27)
					(thickness 0.15)
				)
			)
		)
		(property "Author" "Antmicro"
			(at 185.6 193.8 0)
			(layer "B.Fab")
			(hide yes)
			(effects
				(font
					(size 1 1)
					(thickness 0.15)
				)
				(justify mirror)
			)
		)
		(property "Dielectric" ""
			(at 185.6 193.8 0)
			(layer "B.Fab")
			(hide yes)
			(effects
				(font
					(size 1 1)
					(thickness 0.15)
				)
				(justify mirror)
			)
		)
		(property "License" "Apache-2.0"
			(at 185.6 193.8 0)
			(layer "B.Fab")
			(hide yes)
			(effects
				(font
					(size 1 1)
					(thickness 0.15)
				)
				(justify mirror)
			)
		)
		(property "MPN" "C1608X5R1V475M080AC"
			(at 185.6 193.8 0)
			(layer "B.Fab")
			(hide yes)
			(effects
				(font
					(size 1 1)
					(thickness 0.15)
				)
				(justify mirror)
			)
		)
		(property "Manufacturer" "TDK"
			(at 185.6 193.8 0)
			(layer "B.Fab")
			(hide yes)
			(effects
				(font
					(size 1 1)
					(thickness 0.15)
				)
				(justify mirror)
			)
		)
		(property "Val" "4u7"
			(at 185.6 193.8 0)
			(layer "B.Fab")
			(hide yes)
			(effects
				(font
					(size 1 1)
					(thickness 0.15)
				)
				(justify mirror)
			)
		)
		(property "Voltage" ""
			(at 185.6 193.8 0)
			(layer "B.Fab")
			(hide yes)
			(effects
				(font
					(size 1 1)
					(thickness 0.15)
				)
				(justify mirror)
			)
		)
		(sheetname "/FPGA power supply/")
		(sheetfile "fpga-power-supply.kicad_sch")
		(attr smd)
		(fp_line
			(start -0.15 0.4)
			(end 0.15 0.4)
			(stroke
				(width 0.15)
				(type solid)
			)
			(layer "B.SilkS")
		)
		(fp_line
			(start -0.15 -0.4)
			(end 0.15 -0.4)
			(stroke
				(width 0.15)
				(type solid)
			)
			(layer "B.SilkS")
		)
		(fp_rect
			(start -1.25 0.65)
			(end 1.25 -0.65)
			(stroke
				(width 0.05)
				(type solid)
			)
			(fill no)
			(layer "B.CrtYd")
		)
		(fp_rect
			(start -0.8 0.4)
			(end 0.8 -0.4)
			(stroke
				(width 0.15)
				(type solid)
			)
			(fill no)
			(layer "B.Fab")
		)
		(pad "1" smd roundrect
			(at -0.7 0 180)
			(size 0.8 1)
			(layers "B.Cu" "B.Mask" "B.Paste")
			(roundrect_rratio 0.2)
			(net 1 "GND")
			(pintype "passive")
		)
		(pad "2" smd roundrect
			(at 0.7 0 180)
			(size 0.8 1)
			(layers "B.Cu" "B.Mask" "B.Paste")
			(roundrect_rratio 0.2)
			(net 5 "VCC1V8")
			(pintype "passive")
		)
	)
	(footprint "antmicro-footprints:C_1210_3225Metric"
		(layer "B.Cu")
		(at 76.399 84.5)
		(descr "Capacitor SMD 1210")
		(tags "capacitor SMD 1210")
		(property "Reference" "C145"
			(at -1.399 -1.9 0)
			(layer "B.SilkS")
			(effects
				(font
					(size 0.7 0.7)
					(thickness 0.15)
				)
				(justify right bottom mirror)
			)
		)
		(property "Value" "C_100u_1210"
			(at 0 -2.749 0)
			(layer "B.Fab")
			(effects
				(font
					(size 0.7 0.7)
					(thickness 0.15)
				)
				(justify right bottom mirror)
			)
		)
		(property "Datasheet" "https://product.samsungsem.com/mlcc/CL32A107MQVNNN.do"
			(at 0 0 0)
			(layer "F.Fab")
			(hide yes)
			(effects
				(font
					(size 1.27 1.27)
					(thickness 0.15)
				)
			)
		)
		(property "Description" "SMD Multilayer Ceramic Capacitor, 100 µF, 6.3 V, 1210 [3225 Metric], ± 20%, X5R, CL"
			(at 0 0 0)
			(layer "F.Fab")
			(hide yes)
			(effects
				(font
					(size 1.27 1.27)
					(thickness 0.15)
				)
			)
		)
		(property "Author" "Antmicro"
			(at 0 0 0)
			(layer "B.Fab")
			(hide yes)
			(effects
				(font
					(size 1 1)
					(thickness 0.15)
				)
				(justify mirror)
			)
		)
		(property "Dielectric" ""
			(at 0 0 0)
			(layer "B.Fab")
			(hide yes)
			(effects
				(font
					(size 1 1)
					(thickness 0.15)
				)
				(justify mirror)
			)
		)
		(property "License" "Apache-2.0"
			(at 0 0 0)
			(layer "B.Fab")
			(hide yes)
			(effects
				(font
					(size 1 1)
					(thickness 0.15)
				)
				(justify mirror)
			)
		)
		(property "MPN" "CL32A107MQVNNNE"
			(at 0 0 0)
			(layer "B.Fab")
			(hide yes)
			(effects
				(font
					(size 1 1)
					(thickness 0.15)
				)
				(justify mirror)
			)
		)
		(property "Manufacturer" "Samsung Electro-Mechanics"
			(at 0 0 0)
			(layer "B.Fab")
			(hide yes)
			(effects
				(font
					(size 1 1)
					(thickness 0.15)
				)
				(justify mirror)
			)
		)
		(property "Public" "False"
			(at 0 0 0)
			(layer "B.Fab")
			(hide yes)
			(effects
				(font
					(size 1 1)
					(thickness 0.15)
				)
				(justify mirror)
			)
		)
		(property "Val" "100u"
			(at 0 0 0)
			(layer "B.Fab")
			(hide yes)
			(effects
				(font
					(size 1 1)
					(thickness 0.15)
				)
				(justify mirror)
			)
		)
		(property "Voltage" ""
			(at 0 0 0)
			(layer "B.Fab")
			(hide yes)
			(effects
				(font
					(size 1 1)
					(thickness 0.15)
				)
				(justify mirror)
			)
		)
		(property "DNP" ""
			(at 0 0 0)
			(unlocked yes)
			(layer "B.Fab")
			(hide yes)
			(effects
				(font
					(size 1 1)
					(thickness 0.15)
				)
				(justify mirror)
			)
		)
		(sheetname "/FPGA power supply/")
		(sheetfile "fpga-power-supply.kicad_sch")
		(attr smd)
		(fp_line
			(start -0.3 -1.39)
			(end 0.3 -1.39)
			(stroke
				(width 0.15)
				(type solid)
			)
			(layer "B.SilkS")
		)
		(fp_line
			(start -0.3 1.39)
			(end 0.3 1.39)
			(stroke
				(width 0.15)
				(type solid)
			)
			(layer "B.SilkS")
		)
		(fp_rect
			(start -2.1 1.75)
			(end 2.1 -1.75)
			(stroke
				(width 0.05)
				(type solid)
			)
			(fill no)
			(layer "B.CrtYd")
		)
		(fp_rect
			(start -1.6 1.25)
			(end 1.6 -1.25)
			(stroke
				(width 0.15)
				(type solid)
			)
			(fill no)
			(layer "B.Fab")
		)
		(pad "1" smd rect
			(at -1.145 0)
			(size 1.52 3.05)
			(layers "B.Cu" "B.Mask" "B.Paste")
			(net 1 "GND")
			(pintype "passive")
		)
		(pad "2" smd rect
			(at 1.145 0)
			(size 1.52 3.05)
			(layers "B.Cu" "B.Mask" "B.Paste")
			(net 6 "VCC1V0")
			(pintype "passive")
		)
	)
	(footprint "antmicro-footprints:R_0402_1005Metric"
		(layer "B.Cu")
		(at 81.986 80.3)
		(descr "Resistor SMD 0402")
		(tags "resistor SMD 0402")
		(property "Reference" "R61"
			(at -1.086 -0.558 0)
			(layer "B.SilkS")
			(effects
				(font
					(size 0.7 0.7)
					(thickness 0.15)
				)
				(justify right bottom mirror)
			)
		)
		(property "Value" "R_10k_0402"
			(at 0 -1.4 0)
			(layer "B.Fab")
			(effects
				(font
					(size 0.7 0.7)
					(thickness 0.15)
				)
				(justify right bottom mirror)
			)
		)
		(property "Datasheet" "https://www.bourns.com/docs/product-datasheets/cr.pdf"
			(at 0 0 0)
			(layer "F.Fab")
			(hide yes)
			(effects
				(font
					(size 1.27 1.27)
					(thickness 0.15)
				)
			)
		)
		(property "Description" "SMD Chip Resistor, 10 kohm, ± 1%, 62.5 mW, 0402 [1005 Metric], Thick Film, General Purpose"
			(at 0 0 0)
			(layer "F.Fab")
			(hide yes)
			(effects
				(font
					(size 1.27 1.27)
					(thickness 0.15)
				)
			)
		)
		(property "Author" "Antmicro"
			(at 0 0 0)
			(layer "B.Fab")
			(hide yes)
			(effects
				(font
					(size 1 1)
					(thickness 0.15)
				)
				(justify mirror)
			)
		)
		(property "License" "Apache-2.0"
			(at 0 0 0)
			(layer "B.Fab")
			(hide yes)
			(effects
				(font
					(size 1 1)
					(thickness 0.15)
				)
				(justify mirror)
			)
		)
		(property "MPN" "CR0402-FX-1002GLF"
			(at 0 0 0)
			(layer "B.Fab")
			(hide yes)
			(effects
				(font
					(size 1 1)
					(thickness 0.15)
				)
				(justify mirror)
			)
		)
		(property "Manufacturer" "Bourns"
			(at 0 0 0)
			(layer "B.Fab")
			(hide yes)
			(effects
				(font
					(size 1 1)
					(thickness 0.15)
				)
				(justify mirror)
			)
		)
		(property "Tolerance" "1%"
			(at 0 0 0)
			(layer "B.Fab")
			(hide yes)
			(effects
				(font
					(size 1 1)
					(thickness 0.15)
				)
				(justify mirror)
			)
		)
		(property "Val" "10k"
			(at 0 0 0)
			(layer "B.Fab")
			(hide yes)
			(effects
				(font
					(size 1 1)
					(thickness 0.15)
				)
				(justify mirror)
			)
		)
		(sheetname "/Power supply/")
		(sheetfile "power-supply.kicad_sch")
		(attr smd)
		(fp_rect
			(start -0.925 0.47)
			(end 0.925 -0.47)
			(stroke
				(width 0.05)
				(type default)
			)
			(fill no)
			(layer "B.CrtYd")
		)
		(fp_rect
			(start -0.5 0.25)
			(end 0.5 -0.25)
			(stroke
				(width 0.15)
				(type solid)
			)
			(fill no)
			(layer "B.Fab")
		)
		(pad "1" smd roundrect
			(at -0.48 0)
			(size 0.59 0.64)
			(layers "B.Cu" "B.Mask" "B.Paste")
			(roundrect_rratio 0.25)
			(net 2 "VCC3V3")
			(pintype "passive")
		)
		(pad "2" smd roundrect
			(at 0.48 0)
			(size 0.59 0.64)
			(layers "B.Cu" "B.Mask" "B.Paste")
			(roundrect_rratio 0.25)
			(net 538 "1V0_PG")
			(pintype "passive")
		)
	)
	(footprint "antmicro-footprints:R_0402_1005Metric"
		(layer "B.Cu")
		(at 81.875 94.9)
		(descr "Resistor SMD 0402")
		(tags "resistor SMD 0402")
		(property "Reference" "R91"
			(at -1.086 -0.558 0)
			(layer "B.SilkS")
			(effects
				(font
					(size 0.7 0.7)
					(thickness 0.15)
				)
				(justify right bottom mirror)
			)
		)
		(property "Value" "R_10k_0402"
			(at 0 -1.4 0)
			(layer "B.Fab")
			(effects
				(font
					(size 0.7 0.7)
					(thickness 0.15)
				)
				(justify right bottom mirror)
			)
		)
		(property "Datasheet" "https://www.bourns.com/docs/product-datasheets/cr.pdf"
			(at 0 0 0)
			(layer "F.Fab")
			(hide yes)
			(effects
				(font
					(size 1.27 1.27)
					(thickness 0.15)
				)
			)
		)
		(property "Description" "SMD Chip Resistor, 10 kohm, ± 1%, 62.5 mW, 0402 [1005 Metric], Thick Film, General Purpose"
			(at 0 0 0)
			(layer "F.Fab")
			(hide yes)
			(effects
				(font
					(size 1.27 1.27)
					(thickness 0.15)
				)
			)
		)
		(property "Author" "Antmicro"
			(at 0 0 0)
			(layer "B.Fab")
			(hide yes)
			(effects
				(font
					(size 1 1)
					(thickness 0.15)
				)
				(justify mirror)
			)
		)
		(property "License" "Apache-2.0"
			(at 0 0 0)
			(layer "B.Fab")
			(hide yes)
			(effects
				(font
					(size 1 1)
					(thickness 0.15)
				)
				(justify mirror)
			)
		)
		(property "MPN" "CR0402-FX-1002GLF"
			(at 0 0 0)
			(layer "B.Fab")
			(hide yes)
			(effects
				(font
					(size 1 1)
					(thickness 0.15)
				)
				(justify mirror)
			)
		)
		(property "Manufacturer" "Bourns"
			(at 0 0 0)
			(layer "B.Fab")
			(hide yes)
			(effects
				(font
					(size 1 1)
					(thickness 0.15)
				)
				(justify mirror)
			)
		)
		(property "Tolerance" "1%"
			(at 0 0 0)
			(layer "B.Fab")
			(hide yes)
			(effects
				(font
					(size 1 1)
					(thickness 0.15)
				)
				(justify mirror)
			)
		)
		(property "Val" "10k"
			(at 0 0 0)
			(layer "B.Fab")
			(hide yes)
			(effects
				(font
					(size 1 1)
					(thickness 0.15)
				)
				(justify mirror)
			)
		)
		(sheetname "/Power supply/")
		(sheetfile "power-supply.kicad_sch")
		(attr smd)
		(fp_rect
			(start -0.925 0.47)
			(end 0.925 -0.47)
			(stroke
				(width 0.05)
				(type default)
			)
			(fill no)
			(layer "B.CrtYd")
		)
		(fp_rect
			(start -0.5 0.25)
			(end 0.5 -0.25)
			(stroke
				(width 0.15)
				(type solid)
			)
			(fill no)
			(layer "B.Fab")
		)
		(pad "1" smd roundrect
			(at -0.48 0)
			(size 0.59 0.64)
			(layers "B.Cu" "B.Mask" "B.Paste")
			(roundrect_rratio 0.25)
			(net 4 "VCC5V0")
			(pintype "passive")
		)
		(pad "2" smd roundrect
			(at 0.48 0)
			(size 0.59 0.64)
			(layers "B.Cu" "B.Mask" "B.Paste")
			(roundrect_rratio 0.25)
			(net 292 "/Power supply/1V8_PG")
			(pintype "passive")
		)
	)
)
